(kicad_pcb
	(version 20260206)
	(generator "pcbnew")
	(generator_version "10.0")
	(general
		(thickness 1.6)
		(legacy_teardrops no)
	)
	(paper "A4")
	(title_block
		(title "01162023_DA0F0TEBIF0_F0T_Expander_BD_F_brd_V02_OCP.brd")
		(comment 1 "Grand Teton / footprints 5580-5585 of 9728")
	)
	(layers
		(0 "F.Cu" signal "TOP")
		(4 "In1.Cu" signal "GND")
		(6 "In2.Cu" signal "VCC")
		(8 "In3.Cu" signal "VCC1")
		(10 "In4.Cu" signal "GND1")
		(12 "In5.Cu" signal "IN1")
		(14 "In6.Cu" signal "GND2")
		(16 "In7.Cu" signal "IN2")
		(18 "In8.Cu" signal "GND3")
		(20 "In9.Cu" signal "IN3")
		(22 "In10.Cu" signal "GND4")
		(24 "In11.Cu" signal "IN4")
		(26 "In12.Cu" signal "GND5")
		(28 "In13.Cu" signal "IN5")
		(30 "In14.Cu" signal "GND6")
		(32 "In15.Cu" signal "IN6")
		(34 "In16.Cu" signal "GND7")
		(2 "B.Cu" signal "BOTTOM")
		(9 "F.Adhes" user "F.Adhesive")
		(11 "B.Adhes" user "B.Adhesive")
		(13 "F.Paste" user "Package Geometry/Pastemask Top")
		(15 "B.Paste" user "Package Geometry/Pastemask Bottom")
		(5 "F.SilkS" user "Ref Des/Silkscreen Top")
		(7 "B.SilkS" user "Ref Des/Silkscreen Bottom")
		(1 "F.Mask" user "Board Geometry/Soldermask Top")
		(3 "B.Mask" user "Board Geometry/Soldermask Bottom")
		(17 "Dwgs.User" user "User.Drawings")
		(19 "Cmts.User" user "User.Comments")
		(21 "Eco1.User" user "User.Eco1")
		(23 "Eco2.User" user "User.Eco2")
		(25 "Edge.Cuts" user "Board Geometry/Outline")
		(27 "Margin" user)
		(31 "F.CrtYd" user "Package Geometry/Place Bound Top")
		(29 "B.CrtYd" user "Package Geometry/Place Bound Bottom")
		(35 "F.Fab" user "Ref Des/Assembly Top")
		(33 "B.Fab" user "Ref Des/Assembly Bottom")
	)
	(footprint ""
		(layer "F.Cu")
		(at 342.352884 -116.230654 90)
		(property "Reference" "PR7035"
			(at 0 0 90)
			(layer "F.SilkS")
			(hide yes)
			(effects
				(font
					(size 1.27 1.27)
				)
			)
		)
		(property "Value" ""
			(at 0 0 90)
			(layer "F.Fab")
			(effects
				(font
					(size 1.27 1.27)
				)
			)
		)
		(duplicate_pad_numbers_are_jumpers no)
		(fp_line
			(start 0.7874 -0.4064)
			(end 0.7874 0.4064)
			(stroke
				(width 0.1524)
				(type default)
			)
			(layer "F.SilkS")
		)
		(fp_line
			(start -0.7874 -0.4064)
			(end 0.7874 -0.4064)
			(stroke
				(width 0.1524)
				(type default)
			)
			(layer "F.SilkS")
		)
		(fp_line
			(start 0.7874 0.4064)
			(end -0.7874 0.4064)
			(stroke
				(width 0.1524)
				(type default)
			)
			(layer "F.SilkS")
		)
		(fp_line
			(start -0.7874 0.4064)
			(end -0.7874 -0.4064)
			(stroke
				(width 0.1524)
				(type default)
			)
			(layer "F.SilkS")
		)
		(fp_line
			(start -0.12065 -0.305054)
			(end -0.12065 -0.2794)
			(stroke
				(width 0.1)
				(type default)
			)
			(layer "F.Fab")
		)
		(fp_line
			(start -0.67945 -0.305054)
			(end -0.12065 -0.305054)
			(stroke
				(width 0.1)
				(type default)
			)
			(layer "F.Fab")
		)
		(fp_line
			(start 0.67945 -0.3048)
			(end 0.67945 0.3048)
			(stroke
				(width 0.1)
				(type default)
			)
			(layer "F.Fab")
		)
		(fp_line
			(start 0.12065 -0.3048)
			(end 0.67945 -0.3048)
			(stroke
				(width 0.1)
				(type default)
			)
			(layer "F.Fab")
		)
		(fp_line
			(start 0.12065 -0.2794)
			(end 0.12065 -0.3048)
			(stroke
				(width 0.1)
				(type default)
			)
			(layer "F.Fab")
		)
		(fp_line
			(start -0.12065 -0.2794)
			(end 0.12065 -0.2794)
			(stroke
				(width 0.1)
				(type default)
			)
			(layer "F.Fab")
		)
		(fp_line
			(start 0.120396 0.2794)
			(end -0.12065 0.2794)
			(stroke
				(width 0.1)
				(type default)
			)
			(layer "F.Fab")
		)
		(fp_line
			(start -0.12065 0.2794)
			(end -0.12065 0.3048)
			(stroke
				(width 0.1)
				(type default)
			)
			(layer "F.Fab")
		)
		(fp_line
			(start 0.67945 0.3048)
			(end 0.120396 0.3048)
			(stroke
				(width 0.1)
				(type default)
			)
			(layer "F.Fab")
		)
		(fp_line
			(start 0.120396 0.3048)
			(end 0.120396 0.2794)
			(stroke
				(width 0.1)
				(type default)
			)
			(layer "F.Fab")
		)
		(fp_line
			(start -0.12065 0.3048)
			(end -0.67945 0.3048)
			(stroke
				(width 0.1)
				(type default)
			)
			(layer "F.Fab")
		)
		(fp_line
			(start -0.67945 0.3048)
			(end -0.67945 -0.305054)
			(stroke
				(width 0.1)
				(type default)
			)
			(layer "F.Fab")
		)
		(pad "1" smd circle
			(at -0.40005 0 90)
			(size 0 0)
			(layers "F.Cu" "F.Mask" "F.Paste")
			(net "P12V_NIC5_CO_FLTB")
		)
		(pad "2" smd circle
			(at 0.40005 0 90)
			(size 0 0)
			(layers "F.Cu" "F.Mask" "F.Paste")
			(net "P3V3_AUX")
		)
	)
	(footprint ""
		(layer "F.Cu")
		(at 400.364452 -166.302944 90)
		(property "Reference" "R352"
			(at 0 0 90)
			(layer "F.SilkS")
			(hide yes)
			(effects
				(font
					(size 1.27 1.27)
				)
			)
		)
		(property "Value" ""
			(at 0 0 90)
			(layer "F.Fab")
			(effects
				(font
					(size 1.27 1.27)
				)
			)
		)
		(duplicate_pad_numbers_are_jumpers no)
		(fp_line
			(start 0.7874 -0.4064)
			(end 0.7874 0.4064)
			(stroke
				(width 0.1524)
				(type default)
			)
			(layer "F.SilkS")
		)
		(fp_line
			(start -0.7874 -0.4064)
			(end 0.7874 -0.4064)
			(stroke
				(width 0.1524)
				(type default)
			)
			(layer "F.SilkS")
		)
		(fp_line
			(start 0.7874 0.4064)
			(end -0.7874 0.4064)
			(stroke
				(width 0.1524)
				(type default)
			)
			(layer "F.SilkS")
		)
		(fp_line
			(start -0.7874 0.4064)
			(end -0.7874 -0.4064)
			(stroke
				(width 0.1524)
				(type default)
			)
			(layer "F.SilkS")
		)
		(fp_line
			(start -0.12065 -0.305054)
			(end -0.12065 -0.2794)
			(stroke
				(width 0.1)
				(type default)
			)
			(layer "F.Fab")
		)
		(fp_line
			(start -0.67945 -0.305054)
			(end -0.12065 -0.305054)
			(stroke
				(width 0.1)
				(type default)
			)
			(layer "F.Fab")
		)
		(fp_line
			(start 0.67945 -0.3048)
			(end 0.67945 0.3048)
			(stroke
				(width 0.1)
				(type default)
			)
			(layer "F.Fab")
		)
		(fp_line
			(start 0.12065 -0.3048)
			(end 0.67945 -0.3048)
			(stroke
				(width 0.1)
				(type default)
			)
			(layer "F.Fab")
		)
		(fp_line
			(start 0.12065 -0.2794)
			(end 0.12065 -0.3048)
			(stroke
				(width 0.1)
				(type default)
			)
			(layer "F.Fab")
		)
		(fp_line
			(start -0.12065 -0.2794)
			(end 0.12065 -0.2794)
			(stroke
				(width 0.1)
				(type default)
			)
			(layer "F.Fab")
		)
		(fp_line
			(start 0.120396 0.2794)
			(end -0.12065 0.2794)
			(stroke
				(width 0.1)
				(type default)
			)
			(layer "F.Fab")
		)
		(fp_line
			(start -0.12065 0.2794)
			(end -0.12065 0.3048)
			(stroke
				(width 0.1)
				(type default)
			)
			(layer "F.Fab")
		)
		(fp_line
			(start 0.67945 0.3048)
			(end 0.120396 0.3048)
			(stroke
				(width 0.1)
				(type default)
			)
			(layer "F.Fab")
		)
		(fp_line
			(start 0.120396 0.3048)
			(end 0.120396 0.2794)
			(stroke
				(width 0.1)
				(type default)
			)
			(layer "F.Fab")
		)
		(fp_line
			(start -0.12065 0.3048)
			(end -0.67945 0.3048)
			(stroke
				(width 0.1)
				(type default)
			)
			(layer "F.Fab")
		)
		(fp_line
			(start -0.67945 0.3048)
			(end -0.67945 -0.305054)
			(stroke
				(width 0.1)
				(type default)
			)
			(layer "F.Fab")
		)
		(pad "1" smd circle
			(at -0.40005 0 90)
			(size 0 0)
			(layers "F.Cu" "F.Mask" "F.Paste")
			(net "RST_NIC6_PERST1_R_N")
		)
		(pad "2" smd circle
			(at 0.40005 0 90)
			(size 0 0)
			(layers "F.Cu" "F.Mask" "F.Paste")
			(net "RST_HP_NIC6_BUF_N")
		)
	)
	(footprint ""
		(layer "F.Cu")
		(at 121.441972 -120.087136)
		(property "Reference" "PR6853"
			(at 0 0 0)
			(layer "F.SilkS")
			(hide yes)
			(effects
				(font
					(size 1.27 1.27)
				)
			)
		)
		(property "Value" ""
			(at 0 0 0)
			(layer "F.Fab")
			(effects
				(font
					(size 1.27 1.27)
				)
			)
		)
		(duplicate_pad_numbers_are_jumpers no)
		(fp_line
			(start -0.7874 -0.4064)
			(end 0.7874 -0.4064)
			(stroke
				(width 0.1524)
				(type default)
			)
			(layer "F.SilkS")
		)
		(fp_line
			(start -0.7874 0.4064)
			(end -0.7874 -0.4064)
			(stroke
				(width 0.1524)
				(type default)
			)
			(layer "F.SilkS")
		)
		(fp_line
			(start 0.7874 -0.4064)
			(end 0.7874 0.4064)
			(stroke
				(width 0.1524)
				(type default)
			)
			(layer "F.SilkS")
		)
		(fp_line
			(start 0.7874 0.4064)
			(end -0.7874 0.4064)
			(stroke
				(width 0.1524)
				(type default)
			)
			(layer "F.SilkS")
		)
		(fp_line
			(start -0.67945 -0.305054)
			(end -0.12065 -0.305054)
			(stroke
				(width 0.1)
				(type default)
			)
			(layer "F.Fab")
		)
		(fp_line
			(start -0.67945 0.3048)
			(end -0.67945 -0.305054)
			(stroke
				(width 0.1)
				(type default)
			)
			(layer "F.Fab")
		)
		(fp_line
			(start -0.12065 -0.305054)
			(end -0.12065 -0.2794)
			(stroke
				(width 0.1)
				(type default)
			)
			(layer "F.Fab")
		)
		(fp_line
			(start -0.12065 -0.2794)
			(end 0.12065 -0.2794)
			(stroke
				(width 0.1)
				(type default)
			)
			(layer "F.Fab")
		)
		(fp_line
			(start -0.12065 0.2794)
			(end -0.12065 0.3048)
			(stroke
				(width 0.1)
				(type default)
			)
			(layer "F.Fab")
		)
		(fp_line
			(start -0.12065 0.3048)
			(end -0.67945 0.3048)
			(stroke
				(width 0.1)
				(type default)
			)
			(layer "F.Fab")
		)
		(fp_line
			(start 0.120396 0.2794)
			(end -0.12065 0.2794)
			(stroke
				(width 0.1)
				(type default)
			)
			(layer "F.Fab")
		)
		(fp_line
			(start 0.120396 0.3048)
			(end 0.120396 0.2794)
			(stroke
				(width 0.1)
				(type default)
			)
			(layer "F.Fab")
		)
		(fp_line
			(start 0.12065 -0.3048)
			(end 0.67945 -0.3048)
			(stroke
				(width 0.1)
				(type default)
			)
			(layer "F.Fab")
		)
		(fp_line
			(start 0.12065 -0.2794)
			(end 0.12065 -0.3048)
			(stroke
				(width 0.1)
				(type default)
			)
			(layer "F.Fab")
		)
		(fp_line
			(start 0.67945 -0.3048)
			(end 0.67945 0.3048)
			(stroke
				(width 0.1)
				(type default)
			)
			(layer "F.Fab")
		)
		(fp_line
			(start 0.67945 0.3048)
			(end 0.120396 0.3048)
			(stroke
				(width 0.1)
				(type default)
			)
			(layer "F.Fab")
		)
		(pad "1" smd circle
			(at -0.40005 0)
			(size 0 0)
			(layers "F.Cu" "F.Mask" "F.Paste")
			(net "P3V3_CO_MODE")
		)
		(pad "2" smd circle
			(at 0.40005 0)
			(size 0 0)
			(layers "F.Cu" "F.Mask" "F.Paste")
			(net "GND")
		)
	)
	(footprint ""
		(layer "F.Cu")
		(at 239.16894 -369.8113 90)
		(property "Reference" "PQ6601"
			(at -8.173466 -2.022094 0)
			(unlocked yes)
			(layer "F.SilkS")
			(effects
				(font
					(size 0.7874 0.5842)
					(thickness 0.1524)
				)
				(justify left)
			)
		)
		(property "Value" ""
			(at 0 0 90)
			(layer "F.Fab")
			(effects
				(font
					(size 1.27 1.27)
				)
			)
		)
		(duplicate_pad_numbers_are_jumpers no)
		(fp_line
			(start 2.350008 -2.649982)
			(end 2.350008 -2.4892)
			(stroke
				(width 0.1524)
				(type default)
			)
			(layer "F.SilkS")
		)
		(fp_line
			(start -2.350008 -2.649982)
			(end 2.350008 -2.649982)
			(stroke
				(width 0.1524)
				(type default)
			)
			(layer "F.SilkS")
		)
		(fp_line
			(start -2.350008 -2.4384)
			(end -2.350008 -2.649982)
			(stroke
				(width 0.1524)
				(type default)
			)
			(layer "F.SilkS")
		)
		(fp_line
			(start 2.350008 2.4892)
			(end 2.350008 2.649982)
			(stroke
				(width 0.1524)
				(type default)
			)
			(layer "F.SilkS")
		)
		(fp_line
			(start 2.350008 2.649982)
			(end -2.350008 2.649982)
			(stroke
				(width 0.1524)
				(type default)
			)
			(layer "F.SilkS")
		)
		(fp_line
			(start -2.350008 2.649982)
			(end -2.350008 2.413)
			(stroke
				(width 0.1524)
				(type default)
			)
			(layer "F.SilkS")
		)
		(fp_poly
			(pts
				(xy -4.69519 -2.031238) (xy -5.73659 -2.450338) (xy -5.73659 -1.650238)
			)
			(stroke
				(width 0)
				(type default)
			)
			(fill yes)
			(layer "F.SilkS")
		)
		(fp_line
			(start 2.350008 -2.649982)
			(end 2.350008 2.649982)
			(stroke
				(width 0.1)
				(type default)
			)
			(layer "F.Fab")
		)
		(fp_line
			(start -2.350008 -2.649982)
			(end 2.350008 -2.649982)
			(stroke
				(width 0.1)
				(type default)
			)
			(layer "F.Fab")
		)
		(fp_line
			(start 2.350008 2.649982)
			(end -2.350008 2.649982)
			(stroke
				(width 0.1)
				(type default)
			)
			(layer "F.Fab")
		)
		(fp_line
			(start -2.350008 2.649982)
			(end -2.350008 -2.649982)
			(stroke
				(width 0.1)
				(type default)
			)
			(layer "F.Fab")
		)
		(fp_poly
			(pts
				(xy -3.717544 -1.905) (xy -4.758944 -2.3241) (xy -4.758944 -1.524)
			)
			(stroke
				(width 0)
				(type default)
			)
			(fill yes)
			(layer "F.Fab")
		)
		(pad "1" smd rect
			(at -2.999994 -1.905)
			(size 0.7112 1.1684)
			(layers "F.Cu" "F.Mask" "F.Paste")
			(net "P12V_AUX")
		)
		(pad "2" smd rect
			(at -2.999994 -0.635)
			(size 0.7112 1.1684)
			(layers "F.Cu" "F.Mask" "F.Paste")
			(net "P12V_AUX")
		)
		(pad "3" smd rect
			(at -2.999994 0.635)
			(size 0.7112 1.1684)
			(layers "F.Cu" "F.Mask" "F.Paste")
			(net "P12V_AUX")
		)
		(pad "4" smd rect
			(at -2.999994 1.905)
			(size 0.7112 1.1684)
			(layers "F.Cu" "F.Mask" "F.Paste")
			(net "HS_GATE1_R_1")
		)
		(pad "5" smd circle
			(at 0.925068 0)
			(size 0 0)
			(layers "F.Cu" "F.Mask" "F.Paste")
			(net "P12V_STBY_R1")
		)
		(zone
			(layer "F.Cu")
			(hatch none 0.5)
			(connect_pads
				(clearance 0)
			)
			(min_thickness 0.25)
			(keepout
				(tracks not_allowed)
				(vias allowed)
				(pads allowed)
				(copperpour not_allowed)
				(footprints allowed)
			)
			(placement
				(enabled no)
				(sheetname "")
			)
			(fill
				(thermal_gap 0.5)
				(thermal_bridge_width 0.5)
				(island_removal_mode 0)
			)
			(polygon
				(pts
					(xy 237.00994 -368.3635) (xy 241.32794 -368.3635) (xy 241.81054 -368.3635) (xy 241.81054 -367.4618)
					(xy 236.52734 -367.4618) (xy 236.52734 -368.3635)
				)
			)
		)
	)
	(footprint ""
		(layer "F.Cu")
		(at 321.804284 -356.244906 90)
		(property "Reference" "C539"
			(at 0 0 90)
			(layer "F.SilkS")
			(hide yes)
			(effects
				(font
					(size 1.27 1.27)
				)
			)
		)
		(property "Value" ""
			(at 0 0 90)
			(layer "F.Fab")
			(effects
				(font
					(size 1.27 1.27)
				)
			)
		)
		(duplicate_pad_numbers_are_jumpers no)
		(fp_line
			(start 0.299974 -0.150114)
			(end 0.299974 0.150114)
			(stroke
				(width 0.1)
				(type default)
			)
			(layer "F.Fab")
		)
		(fp_line
			(start -0.299974 -0.150114)
			(end 0.299974 -0.150114)
			(stroke
				(width 0.1)
				(type default)
			)
			(layer "F.Fab")
		)
		(fp_line
			(start 0.299974 0.150114)
			(end -0.299974 0.150114)
			(stroke
				(width 0.1)
				(type default)
			)
			(layer "F.Fab")
		)
		(fp_line
			(start -0.299974 0.150114)
			(end -0.299974 -0.150114)
			(stroke
				(width 0.1)
				(type default)
			)
			(layer "F.Fab")
		)
		(pad "1" smd rect
			(at -0.2667 0 90)
			(size 0.3048 0.381)
			(layers "F.Cu" "F.Mask" "F.Paste")
			(net "P5E_PEX2_STN5_TX_DP<85>")
		)
		(pad "2" smd rect
			(at 0.2667 0 90)
			(size 0.3048 0.381)
			(layers "F.Cu" "F.Mask" "F.Paste")
			(net "P5E_PEX2_STN5_TX_C_DP<85>")
		)
	)
	(footprint ""
		(layer "F.Cu")
		(at 337.566 -201.168 -90)
		(property "Reference" "R4128"
			(at 0 0 270)
			(layer "F.SilkS")
			(hide yes)
			(effects
				(font
					(size 1.27 1.27)
				)
			)
		)
		(property "Value" ""
			(at 0 0 270)
			(layer "F.Fab")
			(effects
				(font
					(size 1.27 1.27)
				)
			)
		)
		(duplicate_pad_numbers_are_jumpers no)
		(fp_line
			(start -0.7874 0.4064)
			(end -0.7874 -0.4064)
			(stroke
				(width 0.1524)
				(type default)
			)
			(layer "F.SilkS")
		)
		(fp_line
			(start 0.7874 0.4064)
			(end -0.7874 0.4064)
			(stroke
				(width 0.1524)
				(type default)
			)
			(layer "F.SilkS")
		)
		(fp_line
			(start -0.7874 -0.4064)
			(end 0.7874 -0.4064)
			(stroke
				(width 0.1524)
				(type default)
			)
			(layer "F.SilkS")
		)
		(fp_line
			(start 0.7874 -0.4064)
			(end 0.7874 0.4064)
			(stroke
				(width 0.1524)
				(type default)
			)
			(layer "F.SilkS")
		)
		(fp_line
			(start -0.67945 0.3048)
			(end -0.67945 -0.305054)
			(stroke
				(width 0.1)
				(type default)
			)
			(layer "F.Fab")
		)
		(fp_line
			(start -0.12065 0.3048)
			(end -0.67945 0.3048)
			(stroke
				(width 0.1)
				(type default)
			)
			(layer "F.Fab")
		)
		(fp_line
			(start 0.120396 0.3048)
			(end 0.120396 0.2794)
			(stroke
				(width 0.1)
				(type default)
			)
			(layer "F.Fab")
		)
		(fp_line
			(start 0.67945 0.3048)
			(end 0.120396 0.3048)
			(stroke
				(width 0.1)
				(type default)
			)
			(layer "F.Fab")
		)
		(fp_line
			(start -0.12065 0.2794)
			(end -0.12065 0.3048)
			(stroke
				(width 0.1)
				(type default)
			)
			(layer "F.Fab")
		)
		(fp_line
			(start 0.120396 0.2794)
			(end -0.12065 0.2794)
			(stroke
				(width 0.1)
				(type default)
			)
			(layer "F.Fab")
		)
		(fp_line
			(start -0.12065 -0.2794)
			(end 0.12065 -0.2794)
			(stroke
				(width 0.1)
				(type default)
			)
			(layer "F.Fab")
		)
		(fp_line
			(start 0.12065 -0.2794)
			(end 0.12065 -0.3048)
			(stroke
				(width 0.1)
				(type default)
			)
			(layer "F.Fab")
		)
		(fp_line
			(start 0.12065 -0.3048)
			(end 0.67945 -0.3048)
			(stroke
				(width 0.1)
				(type default)
			)
			(layer "F.Fab")
		)
		(fp_line
			(start 0.67945 -0.3048)
			(end 0.67945 0.3048)
			(stroke
				(width 0.1)
				(type default)
			)
			(layer "F.Fab")
		)
		(fp_line
			(start -0.67945 -0.305054)
			(end -0.12065 -0.305054)
			(stroke
				(width 0.1)
				(type default)
			)
			(layer "F.Fab")
		)
		(fp_line
			(start -0.12065 -0.305054)
			(end -0.12065 -0.2794)
			(stroke
				(width 0.1)
				(type default)
			)
			(layer "F.Fab")
		)
		(pad "1" smd circle
			(at -0.40005 0 270)
			(size 0 0)
			(layers "F.Cu" "F.Mask" "F.Paste")
			(net "SSD11_PWRDIS")
		)
		(pad "2" smd circle
			(at 0.40005 0 270)
			(size 0 0)
			(layers "F.Cu" "F.Mask" "F.Paste")
			(net "SSD11_PWRDIS_R")
		)
	)
)
